(kicad_pcb
	(version 20260206)
	(generator "pcbnew")
	(generator_version "10.0")
	(general
		(thickness 1.6)
		(legacy_teardrops no)
	)
	(paper "A4")
	(title_block
		(title "Wiwynn_Tioga_Pass_MB.brd")
		(comment 1 "Tioga Pass / footprints 1164-1170 of 4770")
	)
	(layers
		(0 "F.Cu" signal "TOP")
		(4 "In1.Cu" signal "L2GND")
		(6 "In2.Cu" signal "L3")
		(8 "In3.Cu" signal "L4GND")
		(10 "In4.Cu" signal "L5")
		(12 "In5.Cu" signal "L6GND")
		(14 "In6.Cu" signal "L7VCC")
		(16 "In7.Cu" signal "L8VCC")
		(18 "In8.Cu" signal "L9GND")
		(20 "In9.Cu" signal "L10")
		(22 "In10.Cu" signal "L11GND")
		(24 "In11.Cu" signal "L12")
		(26 "In12.Cu" signal "L13GND")
		(2 "B.Cu" signal "BOTTOM")
		(9 "F.Adhes" user "F.Adhesive")
		(11 "B.Adhes" user "B.Adhesive")
		(13 "F.Paste" user "Package Geometry/Pastemask Top")
		(15 "B.Paste" user "Package Geometry/Pastemask Bottom")
		(5 "F.SilkS" user "Ref Des/Silkscreen Top")
		(7 "B.SilkS" user "Ref Des/Silkscreen Bottom")
		(1 "F.Mask" user "Board Geometry/Soldermask Top")
		(3 "B.Mask" user "Board Geometry/Soldermask Bottom")
		(17 "Dwgs.User" user "User.Drawings")
		(19 "Cmts.User" user "User.Comments")
		(21 "Eco1.User" user "User.Eco1")
		(23 "Eco2.User" user "User.Eco2")
		(25 "Edge.Cuts" user "Board Geometry/Outline")
		(27 "Margin" user)
		(31 "F.CrtYd" user "Package Geometry/Place Bound Top")
		(29 "B.CrtYd" user "Package Geometry/Place Bound Bottom")
		(35 "F.Fab" user "Ref Des/Assembly Top")
		(33 "B.Fab" user "Ref Des/Assembly Bottom")
	)
	(footprint ""
		(layer "F.Cu")
		(at 390.271 1.651 -90)
		(property "Reference" "R8G19"
			(at 0 0 270)
			(layer "F.SilkS")
			(hide yes)
			(effects
				(font
					(size 1.27 1.27)
				)
			)
		)
		(property "Value" ""
			(at 0 0 270)
			(layer "F.Fab")
			(effects
				(font
					(size 1.27 1.27)
				)
			)
		)
		(duplicate_pad_numbers_are_jumpers no)
		(fp_poly
			(pts
				(xy -0.2794 -0.1016) (xy 0.2794 -0.1016) (xy 0.2794 0.9906) (xy -0.2794 0.9906)
			)
			(stroke
				(width 0)
				(type default)
			)
			(fill no)
			(layer "F.CrtYd")
		)
		(fp_line
			(start -0.2794 0.9906)
			(end 0.2794 0.9906)
			(stroke
				(width 0.1)
				(type default)
			)
			(layer "F.Fab")
		)
		(fp_line
			(start 0.2794 0.9906)
			(end 0.2794 -0.1016)
			(stroke
				(width 0.1)
				(type default)
			)
			(layer "F.Fab")
		)
		(fp_line
			(start -0.2794 -0.1016)
			(end -0.2794 0.9906)
			(stroke
				(width 0.1)
				(type default)
			)
			(layer "F.Fab")
		)
		(fp_line
			(start 0.2794 -0.1016)
			(end -0.2794 -0.1016)
			(stroke
				(width 0.1)
				(type default)
			)
			(layer "F.Fab")
		)
		(pad "1" smd rect
			(at 0 0 270)
			(size 0.508 0.508)
			(layers "F.Cu" "F.Mask" "F.Paste")
			(net "JTAG_TDI")
		)
		(pad "2" smd rect
			(at 0 0.889 270)
			(size 0.508 0.508)
			(layers "F.Cu" "F.Mask" "F.Paste")
			(net "JTAG_TDI_R")
		)
		(zone
			(layer "F.Cu")
			(hatch none 0.5)
			(connect_pads
				(clearance 0)
			)
			(min_thickness 0.25)
			(keepout
				(tracks not_allowed)
				(vias allowed)
				(pads allowed)
				(copperpour not_allowed)
				(footprints allowed)
			)
			(placement
				(enabled no)
				(sheetname "")
			)
			(fill
				(thermal_gap 0.5)
				(thermal_bridge_width 0.5)
				(island_removal_mode 0)
			)
			(polygon
				(pts
					(xy 389.636 1.397) (xy 389.636 1.905) (xy 390.017 1.905) (xy 390.017 1.397)
				)
			)
		)
		(zone
			(layer "F.Cu")
			(hatch none 0.5)
			(connect_pads
				(clearance 0)
			)
			(min_thickness 0.25)
			(keepout
				(tracks allowed)
				(vias not_allowed)
				(pads allowed)
				(copperpour not_allowed)
				(footprints allowed)
			)
			(placement
				(enabled no)
				(sheetname "")
			)
			(fill
				(thermal_gap 0.5)
				(thermal_bridge_width 0.5)
				(island_removal_mode 0)
			)
			(polygon
				(pts
					(xy 390.017 1.397) (xy 390.017 1.905) (xy 389.636 1.905) (xy 389.636 1.397)
				)
			)
		)
	)
	(footprint ""
		(layer "F.Cu")
		(at 252.1585 -3.3528 -90)
		(property "Reference" "C5G13"
			(at 1.848866 0.752348 270)
			(unlocked yes)
			(layer "F.SilkS")
			(effects
				(font
					(size 1.27 0.9652)
					(thickness 0.1524)
				)
			)
		)
		(property "Value" ""
			(at 0 0 270)
			(layer "F.Fab")
			(effects
				(font
					(size 1.27 1.27)
				)
			)
		)
		(duplicate_pad_numbers_are_jumpers no)
		(fp_rect
			(start -0.500126 1.598422)
			(end 0.500126 -0.201422)
			(stroke
				(width 0)
				(type default)
			)
			(fill no)
			(layer "F.CrtYd")
		)
		(fp_line
			(start -0.500126 1.598422)
			(end -0.500126 -0.201422)
			(stroke
				(width 0.1)
				(type default)
			)
			(layer "F.Fab")
		)
		(fp_line
			(start 0.500126 1.598422)
			(end -0.500126 1.598422)
			(stroke
				(width 0.1)
				(type default)
			)
			(layer "F.Fab")
		)
		(fp_line
			(start -0.500126 -0.201422)
			(end 0.500126 -0.201422)
			(stroke
				(width 0.1)
				(type default)
			)
			(layer "F.Fab")
		)
		(fp_line
			(start 0.500126 -0.201422)
			(end 0.500126 1.598422)
			(stroke
				(width 0.1)
				(type default)
			)
			(layer "F.Fab")
		)
		(pad "1" smd rect
			(at 0 0 180)
			(size 0.889 0.9906)
			(layers "F.Cu" "F.Mask" "F.Paste")
			(net "PVDDQ_ABC")
		)
		(pad "2" smd rect
			(at 0 1.397 180)
			(size 0.889 0.9906)
			(layers "F.Cu" "F.Mask" "F.Paste")
			(net "GND")
		)
		(zone
			(layer "F.Cu")
			(hatch none 0.5)
			(connect_pads
				(clearance 0)
			)
			(min_thickness 0.25)
			(keepout
				(tracks allowed)
				(vias not_allowed)
				(pads allowed)
				(copperpour not_allowed)
				(footprints allowed)
			)
			(placement
				(enabled no)
				(sheetname "")
			)
			(fill
				(thermal_gap 0.5)
				(thermal_bridge_width 0.5)
				(island_removal_mode 0)
			)
			(polygon
				(pts
					(xy 251.206 -3.8481) (xy 251.206 -2.8575) (xy 251.714 -2.8575) (xy 251.714 -3.8481)
				)
			)
		)
		(zone
			(layer "F.Cu")
			(hatch none 0.5)
			(connect_pads
				(clearance 0)
			)
			(min_thickness 0.25)
			(keepout
				(tracks not_allowed)
				(vias allowed)
				(pads allowed)
				(copperpour not_allowed)
				(footprints allowed)
			)
			(placement
				(enabled no)
				(sheetname "")
			)
			(fill
				(thermal_gap 0.5)
				(thermal_bridge_width 0.5)
				(island_removal_mode 0)
			)
			(polygon
				(pts
					(xy 251.206 -3.8481) (xy 251.206 -2.8575) (xy 251.714 -2.8575) (xy 251.714 -3.8481)
				)
			)
		)
	)
	(footprint ""
		(layer "F.Cu")
		(at 414.126172 -48.083978 180)
		(property "Reference" "C25W21"
			(at -0.8382 -0.67818 180)
			(unlocked yes)
			(layer "F.SilkS")
			(effects
				(font
					(size 0.4064 0.254)
					(thickness 0.1524)
				)
				(justify left)
			)
		)
		(property "Value" ""
			(at 0 0 180)
			(layer "F.Fab")
			(effects
				(font
					(size 1.27 1.27)
				)
			)
		)
		(duplicate_pad_numbers_are_jumpers no)
		(fp_poly
			(pts
				(xy 0.3048 -0.1016) (xy 0.3048 0.9906) (xy -0.3048 0.9906) (xy -0.3048 -0.1016)
			)
			(stroke
				(width 0)
				(type default)
			)
			(fill no)
			(layer "F.CrtYd")
		)
		(fp_line
			(start 0.3048 0.9906)
			(end 0.3048 -0.1016)
			(stroke
				(width 0.1)
				(type default)
			)
			(layer "F.Fab")
		)
		(fp_line
			(start 0.3048 -0.1016)
			(end -0.3048 -0.1016)
			(stroke
				(width 0.1)
				(type default)
			)
			(layer "F.Fab")
		)
		(fp_line
			(start -0.3048 0.9906)
			(end 0.3048 0.9906)
			(stroke
				(width 0.1)
				(type default)
			)
			(layer "F.Fab")
		)
		(fp_line
			(start -0.3048 -0.1016)
			(end -0.3048 0.9906)
			(stroke
				(width 0.1)
				(type default)
			)
			(layer "F.Fab")
		)
		(pad "1" smd rect
			(at 0 0 180)
			(size 0.508 0.508)
			(layers "F.Cu" "F.Mask" "F.Paste")
			(net "P2E_SSB_BMC_RX_DN")
		)
		(pad "2" smd rect
			(at 0 0.889 180)
			(size 0.508 0.508)
			(layers "F.Cu" "F.Mask" "F.Paste")
			(net "P2E_SSB_BMC_RX_C_DN")
		)
		(zone
			(layer "F.Cu")
			(hatch none 0.5)
			(connect_pads
				(clearance 0)
			)
			(min_thickness 0.25)
			(keepout
				(tracks not_allowed)
				(vias allowed)
				(pads allowed)
				(copperpour not_allowed)
				(footprints allowed)
			)
			(placement
				(enabled no)
				(sheetname "")
			)
			(fill
				(thermal_gap 0.5)
				(thermal_bridge_width 0.5)
				(island_removal_mode 0)
			)
			(polygon
				(pts
					(xy 414.380172 -48.718978) (xy 413.872172 -48.718978) (xy 413.872172 -48.337978) (xy 414.380172 -48.337978)
				)
			)
		)
		(zone
			(layer "F.Cu")
			(hatch none 0.5)
			(connect_pads
				(clearance 0)
			)
			(min_thickness 0.25)
			(keepout
				(tracks allowed)
				(vias not_allowed)
				(pads allowed)
				(copperpour not_allowed)
				(footprints allowed)
			)
			(placement
				(enabled no)
				(sheetname "")
			)
			(fill
				(thermal_gap 0.5)
				(thermal_bridge_width 0.5)
				(island_removal_mode 0)
			)
			(polygon
				(pts
					(xy 414.380172 -48.337978) (xy 413.872172 -48.337978) (xy 413.872172 -48.718978) (xy 414.380172 -48.718978)
				)
			)
		)
	)
	(footprint ""
		(layer "F.Cu")
		(at 169.926 -86.868 180)
		(property "Reference" "R4D5"
			(at 0 0 180)
			(layer "F.SilkS")
			(hide yes)
			(effects
				(font
					(size 1.27 1.27)
				)
			)
		)
		(property "Value" ""
			(at 0 0 180)
			(layer "F.Fab")
			(effects
				(font
					(size 1.27 1.27)
				)
			)
		)
		(duplicate_pad_numbers_are_jumpers no)
		(fp_poly
			(pts
				(xy -0.2794 -0.1016) (xy 0.2794 -0.1016) (xy 0.2794 0.9906) (xy -0.2794 0.9906)
			)
			(stroke
				(width 0)
				(type default)
			)
			(fill no)
			(layer "F.CrtYd")
		)
		(fp_line
			(start 0.2794 0.9906)
			(end 0.2794 -0.1016)
			(stroke
				(width 0.1)
				(type default)
			)
			(layer "F.Fab")
		)
		(fp_line
			(start 0.2794 -0.1016)
			(end -0.2794 -0.1016)
			(stroke
				(width 0.1)
				(type default)
			)
			(layer "F.Fab")
		)
		(fp_line
			(start -0.2794 0.9906)
			(end 0.2794 0.9906)
			(stroke
				(width 0.1)
				(type default)
			)
			(layer "F.Fab")
		)
		(fp_line
			(start -0.2794 -0.1016)
			(end -0.2794 0.9906)
			(stroke
				(width 0.1)
				(type default)
			)
			(layer "F.Fab")
		)
		(pad "1" smd rect
			(at 0 0 180)
			(size 0.508 0.508)
			(layers "F.Cu" "F.Mask" "F.Paste")
			(net "CLK_100M_CPU0_RC_REFCLK1_R_DN")
		)
		(pad "2" smd rect
			(at 0 0.889 180)
			(size 0.508 0.508)
			(layers "F.Cu" "F.Mask" "F.Paste")
			(net "CLK_100M_CPU0_RC_REFCLK1_DN")
		)
		(zone
			(layer "F.Cu")
			(hatch none 0.5)
			(connect_pads
				(clearance 0)
			)
			(min_thickness 0.25)
			(keepout
				(tracks not_allowed)
				(vias allowed)
				(pads allowed)
				(copperpour not_allowed)
				(footprints allowed)
			)
			(placement
				(enabled no)
				(sheetname "")
			)
			(fill
				(thermal_gap 0.5)
				(thermal_bridge_width 0.5)
				(island_removal_mode 0)
			)
			(polygon
				(pts
					(xy 170.18 -87.503) (xy 169.672 -87.503) (xy 169.672 -87.122) (xy 170.18 -87.122)
				)
			)
		)
		(zone
			(layer "F.Cu")
			(hatch none 0.5)
			(connect_pads
				(clearance 0)
			)
			(min_thickness 0.25)
			(keepout
				(tracks allowed)
				(vias not_allowed)
				(pads allowed)
				(copperpour not_allowed)
				(footprints allowed)
			)
			(placement
				(enabled no)
				(sheetname "")
			)
			(fill
				(thermal_gap 0.5)
				(thermal_bridge_width 0.5)
				(island_removal_mode 0)
			)
			(polygon
				(pts
					(xy 170.18 -87.122) (xy 169.672 -87.122) (xy 169.672 -87.503) (xy 170.18 -87.503)
				)
			)
		)
	)
	(footprint ""
		(layer "F.Cu")
		(at 456.2475 -25.8572 -90)
		(property "Reference" "C9W5"
			(at -0.8382 -0.67818 270)
			(unlocked yes)
			(layer "F.SilkS")
			(effects
				(font
					(size 0.4064 0.254)
					(thickness 0.1524)
				)
				(justify left)
			)
		)
		(property "Value" ""
			(at 0 0 270)
			(layer "F.Fab")
			(effects
				(font
					(size 1.27 1.27)
				)
			)
		)
		(duplicate_pad_numbers_are_jumpers no)
		(fp_poly
			(pts
				(xy 0.3048 -0.1016) (xy 0.3048 0.9906) (xy -0.3048 0.9906) (xy -0.3048 -0.1016)
			)
			(stroke
				(width 0)
				(type default)
			)
			(fill no)
			(layer "F.CrtYd")
		)
		(fp_line
			(start -0.3048 0.9906)
			(end 0.3048 0.9906)
			(stroke
				(width 0.1)
				(type default)
			)
			(layer "F.Fab")
		)
		(fp_line
			(start 0.3048 0.9906)
			(end 0.3048 -0.1016)
			(stroke
				(width 0.1)
				(type default)
			)
			(layer "F.Fab")
		)
		(fp_line
			(start -0.3048 -0.1016)
			(end -0.3048 0.9906)
			(stroke
				(width 0.1)
				(type default)
			)
			(layer "F.Fab")
		)
		(fp_line
			(start 0.3048 -0.1016)
			(end -0.3048 -0.1016)
			(stroke
				(width 0.1)
				(type default)
			)
			(layer "F.Fab")
		)
		(pad "1" smd rect
			(at 0 0 270)
			(size 0.508 0.508)
			(layers "F.Cu" "F.Mask" "F.Paste")
			(net "P3V3_STBY")
		)
		(pad "2" smd rect
			(at 0 0.889 270)
			(size 0.508 0.508)
			(layers "F.Cu" "F.Mask" "F.Paste")
			(net "GND")
		)
		(zone
			(layer "F.Cu")
			(hatch none 0.5)
			(connect_pads
				(clearance 0)
			)
			(min_thickness 0.25)
			(keepout
				(tracks not_allowed)
				(vias allowed)
				(pads allowed)
				(copperpour not_allowed)
				(footprints allowed)
			)
			(placement
				(enabled no)
				(sheetname "")
			)
			(fill
				(thermal_gap 0.5)
				(thermal_bridge_width 0.5)
				(island_removal_mode 0)
			)
			(polygon
				(pts
					(xy 455.6125 -26.1112) (xy 455.6125 -25.6032) (xy 455.9935 -25.6032) (xy 455.9935 -26.1112)
				)
			)
		)
		(zone
			(layer "F.Cu")
			(hatch none 0.5)
			(connect_pads
				(clearance 0)
			)
			(min_thickness 0.25)
			(keepout
				(tracks allowed)
				(vias not_allowed)
				(pads allowed)
				(copperpour not_allowed)
				(footprints allowed)
			)
			(placement
				(enabled no)
				(sheetname "")
			)
			(fill
				(thermal_gap 0.5)
				(thermal_bridge_width 0.5)
				(island_removal_mode 0)
			)
			(polygon
				(pts
					(xy 455.9935 -26.1112) (xy 455.9935 -25.6032) (xy 455.6125 -25.6032) (xy 455.6125 -26.1112)
				)
			)
		)
	)
	(footprint ""
		(layer "F.Cu")
		(at 109.43844 -73.318116)
		(property "Reference" "C3D18"
			(at 0 0 0)
			(layer "F.SilkS")
			(hide yes)
			(effects
				(font
					(size 1.27 1.27)
				)
			)
		)
		(property "Value" ""
			(at 0 0 0)
			(layer "F.Fab")
			(effects
				(font
					(size 1.27 1.27)
				)
			)
		)
		(duplicate_pad_numbers_are_jumpers no)
		(fp_poly
			(pts
				(xy -0.4953 -0.2032) (xy 0.4953 -0.2032) (xy 0.4953 1.6002) (xy -0.4953 1.6002)
			)
			(stroke
				(width 0)
				(type default)
			)
			(fill no)
			(layer "F.CrtYd")
		)
		(fp_line
			(start -0.4953 -0.2032)
			(end 0.4953 -0.2032)
			(stroke
				(width 0.1)
				(type default)
			)
			(layer "F.Fab")
		)
		(fp_line
			(start -0.4953 1.6002)
			(end -0.4953 -0.2032)
			(stroke
				(width 0.1)
				(type default)
			)
			(layer "F.Fab")
		)
		(fp_line
			(start 0.4953 -0.2032)
			(end 0.4953 1.6002)
			(stroke
				(width 0.1)
				(type default)
			)
			(layer "F.Fab")
		)
		(fp_line
			(start 0.4953 1.6002)
			(end -0.4953 1.6002)
			(stroke
				(width 0.1)
				(type default)
			)
			(layer "F.Fab")
		)
		(pad "1" smd rect
			(at 0 0)
			(size 0.762 0.889)
			(layers "F.Cu" "F.Mask" "F.Paste")
			(net "PVCCMCP_CPU1")
		)
		(pad "2" smd rect
			(at 0 1.397)
			(size 0.762 0.889)
			(layers "F.Cu" "F.Mask" "F.Paste")
			(net "GND")
		)
		(zone
			(layer "F.Cu")
			(hatch none 0.5)
			(connect_pads
				(clearance 0)
			)
			(min_thickness 0.25)
			(keepout
				(tracks not_allowed)
				(vias allowed)
				(pads allowed)
				(copperpour not_allowed)
				(footprints allowed)
			)
			(placement
				(enabled no)
				(sheetname "")
			)
			(fill
				(thermal_gap 0.5)
				(thermal_bridge_width 0.5)
				(island_removal_mode 0)
			)
			(polygon
				(pts
					(xy 109.05744 -72.873616) (xy 109.81944 -72.873616) (xy 109.81944 -72.365616) (xy 109.05744 -72.365616)
				)
			)
		)
	)
	(footprint ""
		(layer "F.Cu")
		(at 0.55118 -12.97432 90)
		(property "Reference" "C1G11"
			(at 0 0 90)
			(layer "F.SilkS")
			(hide yes)
			(effects
				(font
					(size 1.27 1.27)
				)
			)
		)
		(property "Value" ""
			(at 0 0 90)
			(layer "F.Fab")
			(effects
				(font
					(size 1.27 1.27)
				)
			)
		)
		(duplicate_pad_numbers_are_jumpers no)
		(fp_rect
			(start -0.3048 -0.1016)
			(end 0.3048 0.9906)
			(stroke
				(width 0)
				(type default)
			)
			(fill no)
			(layer "F.CrtYd")
		)
		(fp_line
			(start 0.3048 -0.1016)
			(end -0.3048 -0.1016)
			(stroke
				(width 0.1)
				(type default)
			)
			(layer "F.Fab")
		)
		(fp_line
			(start -0.3048 -0.1016)
			(end -0.3048 0.9906)
			(stroke
				(width 0.1)
				(type default)
			)
			(layer "F.Fab")
		)
		(fp_line
			(start 0.3048 0.9906)
			(end 0.3048 -0.1016)
			(stroke
				(width 0.1)
				(type default)
			)
			(layer "F.Fab")
		)
		(fp_line
			(start -0.3048 0.9906)
			(end 0.3048 0.9906)
			(stroke
				(width 0.1)
				(type default)
			)
			(layer "F.Fab")
		)
		(pad "1" smd rect
			(at 0 0 90)
			(size 0.508 0.508)
			(layers "F.Cu" "F.Mask" "F.Paste")
			(net "VR_PVDDQ_GHJ_PH1_BOOT")
		)
		(pad "2" smd rect
			(at 0 0.889 90)
			(size 0.508 0.508)
			(layers "F.Cu" "F.Mask" "F.Paste")
			(net "VR_PVDDQ_GHJ_PH1_PHASE")
		)
		(zone
			(layer "F.Cu")
			(hatch none 0.5)
			(connect_pads
				(clearance 0)
			)
			(min_thickness 0.25)
			(keepout
				(tracks not_allowed)
				(vias allowed)
				(pads allowed)
				(copperpour not_allowed)
				(footprints allowed)
			)
			(placement
				(enabled no)
				(sheetname "")
			)
			(fill
				(thermal_gap 0.5)
				(thermal_bridge_width 0.5)
				(island_removal_mode 0)
			)
			(polygon
				(pts
					(xy 0.80518 -12.72032) (xy 1.18618 -12.72032) (xy 1.18618 -13.22832) (xy 0.80518 -13.22832)
				)
			)
		)
		(zone
			(layer "F.Cu")
			(hatch none 0.5)
			(connect_pads
				(clearance 0)
			)
			(min_thickness 0.25)
			(keepout
				(tracks allowed)
				(vias not_allowed)
				(pads allowed)
				(copperpour not_allowed)
				(footprints allowed)
			)
			(placement
				(enabled no)
				(sheetname "")
			)
			(fill
				(thermal_gap 0.5)
				(thermal_bridge_width 0.5)
				(island_removal_mode 0)
			)
			(polygon
				(pts
					(xy 0.80518 -12.72032) (xy 1.18618 -12.72032) (xy 1.18618 -13.22832) (xy 0.80518 -13.22832)
				)
			)
		)
	)
)
